(kicad_pcb
	(version 20241229)
	(generator "pcbnew")
	(generator_version "9.0")
	(general
		(thickness 1.294)
		(legacy_teardrops no)
	)
	(paper "A3")
	(title_block
		(title "Kintex 410T devboard")
		(date "2024-04-03")
		(rev "1.1.2")
		(comment 9 "footprints 272-276 of 975")
	)
	(layers
		(0 "F.Cu" mixed)
		(4 "In1.Cu" power)
		(6 "In2.Cu" power)
		(8 "In3.Cu" mixed)
		(10 "In4.Cu" power)
		(12 "In5.Cu" mixed)
		(14 "In6.Cu" power)
		(16 "In7.Cu" mixed)
		(18 "In8.Cu" power)
		(2 "B.Cu" mixed)
		(9 "F.Adhes" user "F.Adhesive")
		(11 "B.Adhes" user "B.Adhesive")
		(13 "F.Paste" user)
		(15 "B.Paste" user)
		(5 "F.SilkS" user "F.Silkscreen")
		(7 "B.SilkS" user "B.Silkscreen")
		(1 "F.Mask" user)
		(3 "B.Mask" user)
		(17 "Dwgs.User" user "User.Drawings")
		(19 "Cmts.User" user "User.Comments")
		(21 "Eco1.User" user "User.Eco1")
		(23 "Eco2.User" user "User.Eco2")
		(25 "Edge.Cuts" user)
		(27 "Margin" user)
		(31 "F.CrtYd" user "F.Courtyard")
		(29 "B.CrtYd" user "B.Courtyard")
		(35 "F.Fab" user)
		(33 "B.Fab" user)
	)
	(footprint "antmicro-footprints:C_0603_1608Metric"
		(layer "F.Cu")
		(at 195.6 155.349)
		(descr "Capacitor SMD 0603")
		(tags "capacitor 0603")
		(property "Reference" "C360"
			(at -3.85 0.351 0)
			(layer "F.SilkS")
			(effects
				(font
					(size 0.7 0.7)
					(thickness 0.15)
				)
				(justify left bottom)
			)
		)
		(property "Value" "C_22u_0603"
			(at 0 1.6 0)
			(layer "F.Fab")
			(effects
				(font
					(size 0.7 0.7)
					(thickness 0.15)
				)
				(justify left bottom)
			)
		)
		(property "Description" "SMD Multilayer Ceramic Capacitor, 22 µF, 6.3 V, 0603 [1608 Metric], ± 20%, X5R, GRM Series"
			(at 0 0 0)
			(layer "F.Fab")
			(hide yes)
			(effects
				(font
					(size 1.27 1.27)
					(thickness 0.15)
				)
			)
		)
		(property "Author" "Antmicro"
			(at 0 0 0)
			(layer "F.Fab")
			(hide yes)
			(effects
				(font
					(size 1 1)
					(thickness 0.15)
				)
			)
		)
		(property "Dielectric" ""
			(at 0 0 0)
			(layer "F.Fab")
			(hide yes)
			(effects
				(font
					(size 1 1)
					(thickness 0.15)
				)
			)
		)
		(property "License" "Apache-2.0"
			(at 0 0 0)
			(layer "F.Fab")
			(hide yes)
			(effects
				(font
					(size 1 1)
					(thickness 0.15)
				)
			)
		)
		(property "MPN" "GRM188R60J226MEA0D"
			(at 0 0 0)
			(layer "F.Fab")
			(hide yes)
			(effects
				(font
					(size 1 1)
					(thickness 0.15)
				)
			)
		)
		(property "Manufacturer" "Murata"
			(at 0 0 0)
			(layer "F.Fab")
			(hide yes)
			(effects
				(font
					(size 1 1)
					(thickness 0.15)
				)
			)
		)
		(property "Val" "22u"
			(at 0 0 0)
			(layer "F.Fab")
			(hide yes)
			(effects
				(font
					(size 1 1)
					(thickness 0.15)
				)
			)
		)
		(property "Voltage" ""
			(at 0 0 0)
			(layer "F.Fab")
			(hide yes)
			(effects
				(font
					(size 1 1)
					(thickness 0.15)
				)
			)
		)
		(sheetname "DC-DC Converters")
		(sheetfile "dc-dc.kicad_sch")
		(attr smd)
		(fp_line
			(start -0.15 -0.4)
			(end 0.15 -0.4)
			(stroke
				(width 0.15)
				(type solid)
			)
			(layer "F.SilkS")
		)
		(fp_line
			(start -0.15 0.4)
			(end 0.15 0.4)
			(stroke
				(width 0.15)
				(type solid)
			)
			(layer "F.SilkS")
		)
		(fp_rect
			(start -1.25 -0.65)
			(end 1.25 0.65)
			(stroke
				(width 0.05)
				(type solid)
			)
			(fill no)
			(layer "F.CrtYd")
		)
		(fp_rect
			(start -0.8 -0.4)
			(end 0.8 0.4)
			(stroke
				(width 0.15)
				(type solid)
			)
			(fill no)
			(layer "F.Fab")
		)
		(pad "1" smd roundrect
			(at -0.7 0)
			(size 0.8 1)
			(layers "F.Cu" "F.Mask" "F.Paste")
			(roundrect_rratio 0.2)
			(net 1 "GND")
			(pintype "passive")
		)
		(pad "2" smd roundrect
			(at 0.7 0)
			(size 0.8 1)
			(layers "F.Cu" "F.Mask" "F.Paste")
			(roundrect_rratio 0.2)
			(net 751 "/DC-DC Converters/1V0_REG")
			(pintype "passive")
		)
	)
	(footprint "antmicro-footprints:SW_KMR211NGLFS_SMD"
		(layer "F.Cu")
		(at 266.8 88.6 180)
		(property "Reference" "S4"
			(at 0.7 -2.6 180)
			(layer "F.SilkS")
			(effects
				(font
					(size 0.7 0.7)
					(thickness 0.15)
				)
				(justify left bottom)
			)
		)
		(property "Value" "SW_KMR211NGLFS_SMD"
			(at -3 3 180)
			(layer "F.Fab")
			(effects
				(font
					(size 0.7 0.7)
					(thickness 0.15)
				)
				(justify left bottom)
			)
		)
		(property "Description" "Tactile Switch, KMR 2 Series, Top Actuated, Surface Mount, Oval Button, 120 gf, 50mA at 32VDC"
			(at 0 0 180)
			(layer "F.Fab")
			(hide yes)
			(effects
				(font
					(size 1.27 1.27)
					(thickness 0.15)
				)
			)
		)
		(property "Author" "Antmicro"
			(at 533.6 177.2 0)
			(layer "F.Fab")
			(hide yes)
			(effects
				(font
					(size 1 1)
					(thickness 0.15)
				)
			)
		)
		(property "License" "Apache-2.0"
			(at 533.6 177.2 0)
			(layer "F.Fab")
			(hide yes)
			(effects
				(font
					(size 1 1)
					(thickness 0.15)
				)
			)
		)
		(property "MPN" "KMR211NGLFS"
			(at 533.6 177.2 0)
			(layer "F.Fab")
			(hide yes)
			(effects
				(font
					(size 1 1)
					(thickness 0.15)
				)
			)
		)
		(property "Manufacturer" "C&K"
			(at 533.6 177.2 0)
			(layer "F.Fab")
			(hide yes)
			(effects
				(font
					(size 1 1)
					(thickness 0.15)
				)
			)
		)
		(sheetname "User GPIO + LED + button + DIP switch")
		(sheetfile "user-gpio.kicad_sch")
		(attr smd)
		(fp_line
			(start 2.101 1.601)
			(end 2.101 1.48)
			(stroke
				(width 0.15)
				(type solid)
			)
			(layer "F.SilkS")
		)
		(fp_line
			(start 2.101 1.601)
			(end -2.1 1.601)
			(stroke
				(width 0.15)
				(type solid)
			)
			(layer "F.SilkS")
		)
		(fp_line
			(start 2.101 -1.58)
			(end 2.101 -1.459)
			(stroke
				(width 0.15)
				(type solid)
			)
			(layer "F.SilkS")
		)
		(fp_line
			(start 2.101 -1.6)
			(end -2.1 -1.6)
			(stroke
				(width 0.15)
				(type solid)
			)
			(layer "F.SilkS")
		)
		(fp_line
			(start -2.1 1.601)
			(end -2.1 1.48)
			(stroke
				(width 0.15)
				(type solid)
			)
			(layer "F.SilkS")
		)
		(fp_line
			(start -2.1 -1.6)
			(end -2.1 -1.499)
			(stroke
				(width 0.15)
				(type solid)
			)
			(layer "F.SilkS")
		)
		(fp_rect
			(start 2.751 1.75)
			(end -2.748 -1.749)
			(stroke
				(width 0.05)
				(type solid)
			)
			(fill no)
			(layer "F.CrtYd")
		)
		(fp_line
			(start 2.101 1.601)
			(end 2.101 -1.6)
			(stroke
				(width 0.15)
				(type solid)
			)
			(layer "F.Fab")
		)
		(fp_line
			(start 2.101 -1.6)
			(end -2.1 -1.6)
			(stroke
				(width 0.15)
				(type solid)
			)
			(layer "F.Fab")
		)
		(fp_line
			(start 0.25 0.802)
			(end -0.248 0.802)
			(stroke
				(width 0.15)
				(type solid)
			)
			(layer "F.Fab")
		)
		(fp_line
			(start -0.248 -0.8)
			(end 0.25 -0.8)
			(stroke
				(width 0.15)
				(type solid)
			)
			(layer "F.Fab")
		)
		(fp_line
			(start -2.1 1.601)
			(end 2.101 1.601)
			(stroke
				(width 0.15)
				(type solid)
			)
			(layer "F.Fab")
		)
		(fp_line
			(start -2.1 -1.6)
			(end -2.1 1.601)
			(stroke
				(width 0.15)
				(type solid)
			)
			(layer "F.Fab")
		)
		(fp_arc
			(start 0.25 -0.8)
			(mid 1.051001 0.001)
			(end 0.25 0.802)
			(stroke
				(width 0.15)
				(type solid)
			)
			(layer "F.Fab")
		)
		(fp_arc
			(start -0.248 0.802)
			(mid -1.050001 0.001)
			(end -0.248 -0.8)
			(stroke
				(width 0.15)
				(type solid)
			)
			(layer "F.Fab")
		)
		(pad "1" smd rect
			(at -2.048 -0.8)
			(size 0.9 1)
			(layers "F.Cu" "F.Mask" "F.Paste")
			(net 1233 "/USER_IO.BUTTON2")
			(pinfunction "1")
			(pintype "passive")
		)
		(pad "2" smd rect
			(at 2.05 -0.8)
			(size 0.9 1)
			(layers "F.Cu" "F.Mask" "F.Paste")
			(net 1233 "/USER_IO.BUTTON2")
			(pinfunction "2")
			(pintype "passive")
		)
		(pad "3" smd rect
			(at -2.048 0.802)
			(size 0.9 1)
			(layers "F.Cu" "F.Mask" "F.Paste")
			(net 1 "GND")
			(pinfunction "3")
			(pintype "passive")
		)
		(pad "4" smd rect
			(at 2.05 0.802)
			(size 0.9 1)
			(layers "F.Cu" "F.Mask" "F.Paste")
			(net 1 "GND")
			(pinfunction "4")
			(pintype "passive")
		)
	)
	(footprint "antmicro-footprints:SOT-23-5"
		(layer "F.Cu")
		(at 258.4 142.9 90)
		(property "Reference" "U15"
			(at -1.1 2.75 90)
			(layer "F.SilkS")
			(effects
				(font
					(size 0.7 0.7)
					(thickness 0.15)
				)
				(justify left bottom)
			)
		)
		(property "Value" "NCP718BSN330T1G"
			(at 0.002 2.799 90)
			(layer "F.Fab")
			(effects
				(font
					(size 0.7 0.7)
					(thickness 0.15)
				)
				(justify left bottom)
			)
		)
		(property "Description" "Linear Voltage Regulator IC Positive Fixed 1 Output 300mA TSOT-23-5"
			(at 0 0 90)
			(layer "F.Fab")
			(hide yes)
			(effects
				(font
					(size 1.27 1.27)
					(thickness 0.15)
				)
			)
		)
		(property "Author" "Antmicro"
			(at 401.3 -115.5 0)
			(layer "F.Fab")
			(hide yes)
			(effects
				(font
					(size 1 1)
					(thickness 0.15)
				)
			)
		)
		(property "License" "Apache-2.0"
			(at 401.3 -115.5 0)
			(layer "F.Fab")
			(hide yes)
			(effects
				(font
					(size 1 1)
					(thickness 0.15)
				)
			)
		)
		(property "MPN" "NCP718BSN330T1G"
			(at 401.3 -115.5 0)
			(layer "F.Fab")
			(hide yes)
			(effects
				(font
					(size 1 1)
					(thickness 0.15)
				)
			)
		)
		(property "Manufacturer" "ON Semiconductor"
			(at 401.3 -115.5 0)
			(layer "F.Fab")
			(hide yes)
			(effects
				(font
					(size 1 1)
					(thickness 0.15)
				)
			)
		)
		(sheetname "USB PHY")
		(sheetfile "usb-phy.kicad_sch")
		(attr smd)
		(fp_line
			(start 0.8 -1.6)
			(end 0.5 -1.6)
			(stroke
				(width 0.15)
				(type solid)
			)
			(layer "F.SilkS")
		)
		(fp_line
			(start -0.8 -1.6)
			(end -0.5 -1.6)
			(stroke
				(width 0.15)
				(type solid)
			)
			(layer "F.SilkS")
		)
		(fp_line
			(start -0.8 -1.6)
			(end -0.8 -1.3)
			(stroke
				(width 0.15)
				(type solid)
			)
			(layer "F.SilkS")
		)
		(fp_line
			(start 0.8 -1.3)
			(end 0.8 -1.6)
			(stroke
				(width 0.15)
				(type solid)
			)
			(layer "F.SilkS")
		)
		(fp_line
			(start 0.8 0.55)
			(end 0.8 -0.55)
			(stroke
				(width 0.15)
				(type solid)
			)
			(layer "F.SilkS")
		)
		(fp_line
			(start 0.8 1.3)
			(end 0.8 1.599)
			(stroke
				(width 0.15)
				(type solid)
			)
			(layer "F.SilkS")
		)
		(fp_line
			(start 0.8 1.599)
			(end 0.549 1.599)
			(stroke
				(width 0.15)
				(type solid)
			)
			(layer "F.SilkS")
		)
		(fp_line
			(start -0.55 1.6)
			(end -0.85 1.6)
			(stroke
				(width 0.15)
				(type solid)
			)
			(layer "F.SilkS")
		)
		(fp_line
			(start -0.85 1.6)
			(end -0.85 1.301)
			(stroke
				(width 0.15)
				(type solid)
			)
			(layer "F.SilkS")
		)
		(fp_circle
			(center -1.25 -1.5)
			(end -1.2 -1.5)
			(stroke
				(width 0.15)
				(type solid)
			)
			(fill yes)
			(layer "F.SilkS")
		)
		(fp_rect
			(start 1.9 -1.76)
			(end -1.9 1.75)
			(stroke
				(width 0.05)
				(type solid)
			)
			(fill no)
			(layer "F.CrtYd")
		)
		(fp_line
			(start -0.398 -1.526)
			(end -0.874 -1.05)
			(stroke
				(width 0.15)
				(type solid)
			)
			(layer "F.Fab")
		)
		(fp_rect
			(start 0.874 1.523)
			(end -0.873 -1.525)
			(stroke
				(width 0.15)
				(type solid)
			)
			(fill no)
			(layer "F.Fab")
		)
		(pad "1" smd rect
			(at -1.351 -0.951)
			(size 0.55 1)
			(layers "F.Cu" "F.Mask" "F.Paste")
			(net 704 "/Power supply/USB_DBG_PD.VBUS")
			(pinfunction "VIN")
			(pintype "passive")
		)
		(pad "2" smd rect
			(at -1.351 0)
			(size 0.55 1)
			(layers "F.Cu" "F.Mask" "F.Paste")
			(net 1 "GND")
			(pinfunction "GND")
			(pintype "passive")
		)
		(pad "3" smd rect
			(at -1.351 0.949)
			(size 0.55 1)
			(layers "F.Cu" "F.Mask" "F.Paste")
			(net 704 "/Power supply/USB_DBG_PD.VBUS")
			(pinfunction "EN")
			(pintype "passive")
		)
		(pad "4" smd rect
			(at 1.35 0.949)
			(size 0.55 1)
			(layers "F.Cu" "F.Mask" "F.Paste")
			(net 1159 "unconnected-(U15-NC-Pad4)")
			(pinfunction "NC")
			(pintype "no_connect")
		)
		(pad "5" smd rect
			(at 1.35 -0.951)
			(size 0.55 1)
			(layers "F.Cu" "F.Mask" "F.Paste")
			(net 707 "/USB PHY/FTDI_3V3")
			(pinfunction "VOUT")
			(pintype "passive")
		)
	)
	(footprint "antmicro-footprints:TSOT23-6"
		(layer "F.Cu")
		(at 245.199 116.404 180)
		(property "Reference" "U43"
			(at -2.901 1.054 90)
			(layer "F.SilkS")
			(effects
				(font
					(size 0.7 0.7)
					(thickness 0.15)
				)
				(justify right bottom)
			)
		)
		(property "Value" "AP22615A_TSOT26"
			(at 0 2.6 0)
			(layer "F.Fab")
			(effects
				(font
					(size 0.7 0.7)
					(thickness 0.15)
				)
				(justify right bottom)
			)
		)
		(property "Description" "Power Load Distribution Switch, High Side, Active High, 1 Output, 5.5 V, 3.6 A, 0.04 ohm, TSOT-26-6"
			(at 0 0 180)
			(layer "F.Fab")
			(hide yes)
			(effects
				(font
					(size 1.27 1.27)
					(thickness 0.15)
				)
			)
		)
		(property "Author" "Antmicro"
			(at 490.398 232.808 0)
			(layer "F.Fab")
			(hide yes)
			(effects
				(font
					(size 1 1)
					(thickness 0.15)
				)
			)
		)
		(property "License" "Apache-2.0"
			(at 490.398 232.808 0)
			(layer "F.Fab")
			(hide yes)
			(effects
				(font
					(size 1 1)
					(thickness 0.15)
				)
			)
		)
		(property "MPN" "AP22615AWU-7"
			(at 490.398 232.808 0)
			(layer "F.Fab")
			(hide yes)
			(effects
				(font
					(size 1 1)
					(thickness 0.15)
				)
			)
		)
		(property "Manufacturer" "Diodes Incorporated"
			(at 490.398 232.808 0)
			(layer "F.Fab")
			(hide yes)
			(effects
				(font
					(size 1 1)
					(thickness 0.15)
				)
			)
		)
		(sheetname "USB PHY")
		(sheetfile "usb-phy.kicad_sch")
		(attr smd)
		(fp_line
			(start 1 1.55)
			(end 1 1.4)
			(stroke
				(width 0.15)
				(type solid)
			)
			(layer "F.SilkS")
		)
		(fp_line
			(start 1 1.55)
			(end -1 1.55)
			(stroke
				(width 0.15)
				(type solid)
			)
			(layer "F.SilkS")
		)
		(fp_line
			(start 1 -1.497)
			(end 1 -1.375)
			(stroke
				(width 0.15)
				(type solid)
			)
			(layer "F.SilkS")
		)
		(fp_line
			(start 1 -1.497)
			(end -1 -1.5)
			(stroke
				(width 0.15)
				(type solid)
			)
			(layer "F.SilkS")
		)
		(fp_line
			(start -1 1.55)
			(end -1 1.4)
			(stroke
				(width 0.15)
				(type solid)
			)
			(layer "F.SilkS")
		)
		(fp_line
			(start -1 -1.5)
			(end -1 -1.375)
			(stroke
				(width 0.15)
				(type solid)
			)
			(layer "F.SilkS")
		)
		(fp_circle
			(center -1.44 -1.5)
			(end -1.39 -1.5)
			(stroke
				(width 0.15)
				(type solid)
			)
			(fill yes)
			(layer "F.SilkS")
		)
		(fp_rect
			(start 1.93 -1.7)
			(end -1.93 1.7)
			(stroke
				(width 0.05)
				(type solid)
			)
			(fill no)
			(layer "F.CrtYd")
		)
		(fp_line
			(start -0.45 -1.521)
			(end -0.876 -1.096)
			(stroke
				(width 0.15)
				(type solid)
			)
			(layer "F.Fab")
		)
		(fp_rect
			(start 0.875 1.528)
			(end -0.875 -1.525)
			(stroke
				(width 0.15)
				(type solid)
			)
			(fill no)
			(layer "F.Fab")
		)
		(pad "1" smd rect
			(at -1.301 -0.947 90)
			(size 0.7 1.2)
			(layers "F.Cu" "F.Mask" "F.Paste")
			(net 715 "/USB PHY/USB_USR_VBUS")
			(pinfunction "OUT")
			(pintype "power_out")
		)
		(pad "2" smd rect
			(at -1.301 0.004 90)
			(size 0.7 1.2)
			(layers "F.Cu" "F.Mask" "F.Paste")
			(net 1 "GND")
			(pinfunction "GND")
			(pintype "power_in")
		)
		(pad "3" smd rect
			(at -1.301 0.954 90)
			(size 0.7 1.2)
			(layers "F.Cu" "F.Mask" "F.Paste")
			(net 386 "Net-(U43-FLG)")
			(pinfunction "FLG")
			(pintype "output")
		)
		(pad "4" smd rect
			(at 1.299 0.954 90)
			(size 0.7 1.2)
			(layers "F.Cu" "F.Mask" "F.Paste")
			(net 385 "Net-(U43-EN)")
			(pinfunction "EN")
			(pintype "input")
		)
		(pad "5" smd rect
			(at 1.299 0.004 90)
			(size 0.7 1.2)
			(layers "F.Cu" "F.Mask" "F.Paste")
			(net 389 "Net-(U43-ISET)")
			(pinfunction "ISET")
			(pintype "passive")
		)
		(pad "6" smd rect
			(at 1.299 -0.947 90)
			(size 0.7 1.2)
			(layers "F.Cu" "F.Mask" "F.Paste")
			(net 703 "+5V")
			(pinfunction "IN")
			(pintype "power_in")
		)
	)
	(footprint "antmicro-footprints:C_0603_1608Metric"
		(layer "F.Cu")
		(at 186.225 176.399 -90)
		(descr "Capacitor SMD 0603")
		(tags "capacitor 0603")
		(property "Reference" "C208"
			(at -1.049 0.625 90)
			(layer "F.SilkS")
			(effects
				(font
					(size 0.7 0.7)
					(thickness 0.15)
				)
				(justify right bottom)
			)
		)
		(property "Value" "C_1u_25V_0603"
			(at 0 1.6 90)
			(layer "F.Fab")
			(effects
				(font
					(size 0.7 0.7)
					(thickness 0.15)
				)
				(justify right bottom)
			)
		)
		(property "Description" "SMD Multilayer Ceramic Capacitor, 1 µF, 25 V, 0603 [1608 Metric], ± 10%, X5R, CL"
			(at 0 0 270)
			(layer "F.Fab")
			(hide yes)
			(effects
				(font
					(size 1.27 1.27)
					(thickness 0.15)
				)
			)
		)
		(property "Author" "Antmicro"
			(at 9.826 362.624 0)
			(layer "F.Fab")
			(hide yes)
			(effects
				(font
					(size 1 1)
					(thickness 0.15)
				)
			)
		)
		(property "Dielectric" ""
			(at 9.826 362.624 0)
			(layer "F.Fab")
			(hide yes)
			(effects
				(font
					(size 1 1)
					(thickness 0.15)
				)
			)
		)
		(property "License" "Apache-2.0"
			(at 9.826 362.624 0)
			(layer "F.Fab")
			(hide yes)
			(effects
				(font
					(size 1 1)
					(thickness 0.15)
				)
			)
		)
		(property "MPN" "CL10A105KA8NNNC"
			(at 9.826 362.624 0)
			(layer "F.Fab")
			(hide yes)
			(effects
				(font
					(size 1 1)
					(thickness 0.15)
				)
			)
		)
		(property "Manufacturer" "Samsung Electro-Mechanics"
			(at 9.826 362.624 0)
			(layer "F.Fab")
			(hide yes)
			(effects
				(font
					(size 1 1)
					(thickness 0.15)
				)
			)
		)
		(property "Val" "1u"
			(at 9.826 362.624 0)
			(layer "F.Fab")
			(hide yes)
			(effects
				(font
					(size 1 1)
					(thickness 0.15)
				)
			)
		)
		(property "Voltage" "25V"
			(at 9.826 362.624 0)
			(layer "F.Fab")
			(hide yes)
			(effects
				(font
					(size 1 1)
					(thickness 0.15)
				)
			)
		)
		(sheetname "Power supply")
		(sheetfile "power-supply.kicad_sch")
		(attr smd)
		(fp_line
			(start -0.15 0.4)
			(end 0.15 0.4)
			(stroke
				(width 0.15)
				(type solid)
			)
			(layer "F.SilkS")
		)
		(fp_line
			(start -0.15 -0.4)
			(end 0.15 -0.4)
			(stroke
				(width 0.15)
				(type solid)
			)
			(layer "F.SilkS")
		)
		(fp_rect
			(start -1.25 -0.65)
			(end 1.25 0.65)
			(stroke
				(width 0.05)
				(type solid)
			)
			(fill no)
			(layer "F.CrtYd")
		)
		(fp_rect
			(start -0.8 -0.4)
			(end 0.8 0.4)
			(stroke
				(width 0.15)
				(type solid)
			)
			(fill no)
			(layer "F.Fab")
		)
		(pad "1" smd roundrect
			(at -0.7 0 270)
			(size 0.8 1)
			(layers "F.Cu" "F.Mask" "F.Paste")
			(roundrect_rratio 0.2)
			(net 1 "GND")
			(pintype "passive")
		)
		(pad "2" smd roundrect
			(at 0.7 0 270)
			(size 0.8 1)
			(layers "F.Cu" "F.Mask" "F.Paste")
			(roundrect_rratio 0.2)
			(net 702 "VDC")
			(pintype "passive")
		)
	)
)
